FILE_TYPE = CONNECTIVITY;
{Allegro Design Entry HDL 17.2-2016 S081 (4005846) 1/11/2022}
"PAGE_NUMBER" = 229;
0"NC";
1"P12V_SCM_R\g";
2"P3V3_AUX\g";
3"P12V_SCM_R\g";
4"P12V_AUX\g";
5"P12V_AUX\g";
6"P12V_AUX\g";
7"P3V3_AUX\g";
8"P3V3_AUX\g";
9"P3V3_AUX\g";
10"P12V_AUX\g";
11"P3V3_AUX\g";
12"GND\g";
13"GND\g";
14"GND\g";
15"GND\g";
16"GND\g";
17"GND\g";
18"GND\g";
19"GND\g";
20"GND\g";
21"GND\g";
22"GND\g";
23"GND\g";
24"GND\g";
25"GND\g";
26"GND\g";
27"GND\g";
28"GND\g";
29"GND\g";
30"GND\g";
31"GND\g";
32"HP_LVC3_SCM_HSC_PWRGD";
33"P12V_SCM_OV_FB";
34"P12V_SCM_AVIN_PD";
35"P12V_SCM_FAULT_R_N";
36"HP_LVC3_SCM_HSC_PWRGD_R";
37"P12V_SCM_FLTB_N";
38"P12V_SCM_IMON";
39"P12V_SCM_EN_R2";
40"P12V_SCM_TIMER";
41"P12V_SCM_ISET";
42"P12V_SCM_SS";
43"P12V_SCM_GATE";
44"P12V_SCM_EN";
45"HP_LVC3_SCM_HSC_PWRGD";
46"P12V_SCM_FAULT_N";
47"P12V_SCM_PWRGD";
48"P12V_SCM_SENSE";
49"P12V_SCM_REG";
50"P12V_SCM_VCC";
51"P12V_SCM_CB";
52"P12V_SCM_OV";
53"P12V_SCM_UV";
54"P12V_SCM_AVIN_PD";
55"P12V_SCM_FAULT_R_N"VOLTAGE"0";
56"P12V_SCM_UV_R";
57"P12V_SCM_EN_G";
58"P12V_SCM_EN_R";
59"VIRTUAL_RESEAT_FPGA_N";
60"P12V_SCM_ISET_R";
61"FM_SCM_PRSNT1_R_N";
62"FM_SCM_PRSNT1_N";
%"UNIVERSAL_GND"
"1","(-1350,-550)","0","logical_power","I10";
;
CDS_LIB"logical_power"
HDL_POWER"GND";
"A"28;
%"Q_RES"
"2","(-675,-1825)","0","pure_quanta","I11";
;
PART_NUMBER"CS32432FB03"
ROOM"SCM_P12V_BOM2"
MATERIAL"CHIP"
PACK_TYPE"0402LF"
VALUE"24.3K"
TOLERANCE"1%"
WATTAGE"1/16W"
LOCATION"PR3999"
CDS_LIB"pure_quanta"
$SEC"1"
CDS_SEC"1";
"A"
$PN"1"41;
"B"
$PN"2"30;
%"Q_RES"
"2","(-250,-1850)","0","pure_quanta","I12";
;
PART_NUMBER"CS32002FB06"
ROOM"SCM_P12V_BOM2"
WATTAGE"1/16W"
VALUE"20K"
PACK_TYPE"0402LF"
MATERIAL"CHIP"
TOLERANCE"1%"
LOCATION"PR4540"
CDS_LIB"pure_quanta"
$SEC"1"
CDS_SEC"1";
"A"
$PN"1"41;
"B"
$PN"2"60;
%"GND"
"1","(-175,-1500)","0","logical_power","I13";
;
SIZE"1B"
CDS_LIB"logical_power"
HDL_POWER"GND";
"A<SIZE-1..0>\NAC"27;
%"Q_RES"
"1","(-300,-1250)","0","pure_quanta","I14";
;
PART_NUMBER"CS00002JB13"
TOLERANCE"5%"
PACK_TYPE"0402LF"
ROOM"SCM_P12V_BOM2"
VALUE"0"
WATTAGE"1/16W"
MATERIAL"CHIP"
$LOCATION"R3998"
CDS_LIB"pure_quanta"
CDS_LOCATION"R3998"
$SEC"1"
CDS_SEC"1";
"B"
$PN"2"39;
"A"
$PN"1"44;
%"UNIVERSAL_POWER"
"1","(-3350,225)","0","logical_power","I16";
;
HDL_POWER"P3V3_AUX"
CDS_LIB"logical_power";
"A"8;
%"Q_RES"
"1","(-3425,875)","0","pure_quanta","I17";
;
PART_NUMBER"CS00002JB13"
MATERIAL"CHIP"
TOLERANCE"5%"
VALUE"0"
WATTAGE"1/16W"
PACK_TYPE"0402LF"
$LOCATION"R3996"
CDS_LIB"pure_quanta"
CDS_LOCATION"R3996"
$SEC"1"
CDS_SEC"1";
"B"
$PN"2"44;
"A"
$PN"1"59;
%"Q_RES"
"2","(-3125,1150)","0","pure_quanta","I18";
;
PART_NUMBER"CS31002FB08"
VALUE"10K"
MATERIAL"CHIP"
PACK_TYPE"0402LF"
TOLERANCE"1%"
WATTAGE"1/16W"
$LOCATION"R1857"
CDS_LIB"pure_quanta"
CDS_LOCATION"R1857"
$SEC"1"
CDS_SEC"1";
"A"
$PN"1"7;
"B"
$PN"2"44;
%"UNIVERSAL_POWER"
"1","(-3125,1400)","0","logical_power","I19";
;
HDL_POWER"P3V3_AUX"
CDS_LIB"logical_power";
"A"7;
%"Q_RES"
"2","(-3350,0)","2","pure_quanta","I2";
;
PART_NUMBER"CS31002FB08"
TOLERANCE"1%"
WATTAGE"1/16W"
PACK_TYPE"0402LF"
VALUE"10K"
MATERIAL"CHIP"
$LOCATION"R1854"
CDS_LIB"pure_quanta"
CDS_LOCATION"R1854"
$SEC"1"
CDS_SEC"1";
"A"
$PN"1"8;
"B"
$PN"2"62;
%"Q_RES"
"1","(-2625,875)","0","pure_quanta","I20";
;
PART_NUMBER"CS00002JB13"
PACK_TYPE"0402LF"
MATERIAL"EMPTY"
WATTAGE"1/16W"
TOLERANCE"5%"
VALUE"0"
ROOM"SCM_P12V_BOM1"
$LOCATION"R4062"
CDS_LIB"pure_quanta"
CDS_LOCATION"R4062"
$SEC"1"
CDS_SEC"1";
"B"
$PN"2"58;
"A"
$PN"1"44;
%"MOSFET_NCH_DUAL"
"1","(-1775,925)","0","pure_quanta","I21";
;
PART_NUMBER"BAM138K0003"
MATERIAL"EMPTY"
ROOM"SCM_P12V_BOM1"
PART_TYPE"SMLF"
VALUE"PJT138K"
$LOCATION"Q125"
NEEDS_NO_SIZE"TRUE"
CDS_LMAN_SYM_OUTLINE"-150,150,150,-150"
CDS_LIB"pure_quanta"
CDS_LOCATION"Q125"
$SEC"1"
CDS_SEC"1";
"D1"
$PN"6"57;
"G1"
$PN"2"58;
"S1"
$PN"1"26;
%"GND"
"1","(-1725,575)","0","logical_power","I22";
;
CDS_LIB"logical_power"
SIZE"1B"
HDL_POWER"GND";
"A<SIZE-1..0>\NAC"26;
%"GND"
"1","(-1050,950)","0","logical_power","I23";
;
SIZE"1B"
CDS_LIB"logical_power"
HDL_POWER"GND";
"A<SIZE-1..0>\NAC"25;
%"Q_RES"
"2","(-1725,1525)","0","pure_quanta","I24";
;
PART_NUMBER"CS31002FB08"
TOLERANCE"1%"
WATTAGE"1/16W"
MATERIAL"EMPTY"
VALUE"10K"
PACK_TYPE"0402LF"
ROOM"SCM_P12V_BOM1"
$LOCATION"R4071"
CDS_LIB"pure_quanta"
CDS_LOCATION"R4071"
$SEC"1"
CDS_SEC"1";
"A"
$PN"1"6;
"B"
$PN"2"57;
%"UNIVERSAL_POWER"
"1","(-1725,1775)","0","logical_power","I25";
;
HDL_POWER"P12V_AUX"
CDS_LIB"logical_power";
"A"6;
%"MOSFET_NCH_DUAL"
"2","(-1100,1275)","0","pure_quanta","I26";
;
PART_NUMBER"BAM138K0003"
PART_TYPE"SMLF"
VALUE"PJT138K"
ROOM"SCM_P12V_BOM1"
MATERIAL"EMPTY"
$LOCATION"Q125"
CDS_LIB"pure_quanta"
CDS_LMAN_SYM_OUTLINE"-150,150,150,-150"
NEEDS_NO_SIZE"TRUE"
CDS_LOCATION"Q125"
$SEC"2"
CDS_SEC"2";
"S2"
$PN"4"25;
"G2"
$PN"5"57;
"D2"
$PN"3"56;
%"Q_RES"
"1","(-500,1600)","0","pure_quanta","I27";
;
PART_NUMBER"CS00002JB13"
WATTAGE"1/16W"
TOLERANCE"5%"
ROOM"SCM_P12V_BOM1"
MATERIAL"EMPTY"
VALUE"0"
PACK_TYPE"0402LF"
$LOCATION"R3997"
CDS_LIB"pure_quanta"
CDS_LOCATION"R3997"
$SEC"1"
CDS_SEC"1";
"B"
$PN"2"53;
"A"
$PN"1"56;
%"GND"
"1","(-500,1850)","0","logical_power","I28";
;
SIZE"1B"
CDS_LIB"logical_power"
HDL_POWER"GND";
"A<SIZE-1..0>\NAC"24;
%"DIODE_TVS"
"1","(-650,2250)","1","pure_quanta","I29";
;
PART_NUMBER"BCSMF14AZ01"
MATERIAL"IC"
VALUE"SMF14A"
LOCATION"PD115"
PIN_NAMES_ROTATE"TRUE"
CDS_LIB"pure_quanta"
CDS_LMAN_SYM_OUTLINE"-100,50,100,-50"
PART_TYPE"SMLF"
$SEC"1"
CDS_SEC"1";
"C"
$PN"C"
Pin_Length"SHORT"5;
"A"
$PN"A"24;
%"Q_RES"
"1","(-2400,-225)","0","pure_quanta","I3";
;
PART_NUMBER"CS11002FB07"
TOLERANCE"1%"
WATTAGE"1/16W"
MATERIAL"CHIP"
PACK_TYPE"0402LF"
VALUE"100"
$LOCATION"R1856"
CDS_LIB"pure_quanta"
CDS_LOCATION"R1856"
$SEC"1"
CDS_SEC"1";
"B"
$PN"2"61;
"A"
$PN"1"62;
%"UNIVERSAL_POWER"
"1","(-500,2575)","0","logical_power","I30";
;
HDL_POWER"P12V_AUX"
CDS_LIB"logical_power";
"A"5;
%"Q_CAP"
"1","(-275,2225)","0","pure_quanta","I31";
;
PART_NUMBER"CH5104KEB02"
MATERIAL"X6S"
VOLTAGE"25V"
VALUE"1UF"
PACK_TYPE"C0402"
LOCATION"PC2230"
CDS_LIB"pure_quanta"
TOLERANCE"10%"
$SEC"1"
CDS_SEC"1";
"B"
$PN"2"24;
"A"
$PN"1"5;
%"GND"
"1","(225,-2150)","0","logical_power","I32";
;
CDS_LIB"logical_power"
SIZE"1B"
HDL_POWER"GND";
"A<SIZE-1..0>\NAC"23;
%"Q_CAP"
"1","(225,-1925)","0","pure_quanta","I33";
;
PART_NUMBER"CH3474K1B04"
MATERIAL"X7R"
VOLTAGE"25V"
VALUE"0.047UF"
PACK_TYPE"C0402"
ROOM"SCM_P12V_BOM2"
LOCATION"PC2232"
TOLERANCE"10%"
CDS_LIB"pure_quanta"
$SEC"1"
CDS_SEC"1";
"B"
$PN"2"23;
"A"
$PN"1"42;
%"Q_RES"
"2","(1650,-2125)","0","pure_quanta","I34";
;
PART_NUMBER"CS33012FB03"
VALUE"30.1K"
TOLERANCE"1%"
WATTAGE"1/16W"
MATERIAL"CHIP"
PACK_TYPE"0402LF"
ROOM"SCM_P12V_BOM2"
LOCATION"PR4005"
CDS_LIB"pure_quanta"
$SEC"1"
CDS_SEC"1";
"A"
$PN"1"38;
"B"
$PN"2"20;
%"GND"
"1","(150,-1075)","0","logical_power","I35";
;
CDS_LIB"logical_power"
SIZE"1B"
HDL_POWER"GND";
"A<SIZE-1..0>\NAC"22;
%"GND"
"1","(566,-1984)","0","logical_power","I36";
;
SIZE"1B"
CDS_LIB"logical_power"
HDL_POWER"GND";
"A<SIZE-1..0>\NAC"21;
%"Q_CAP"
"1","(150,-850)","0","pure_quanta","I37";
;
PART_NUMBER"CH5104KEB02"
ROOM"SCM_P12V_BOM2"
VOLTAGE"25V"
VALUE"1UF"
PACK_TYPE"C0402"
MATERIAL"X6S"
LOCATION"PC2231"
TOLERANCE"10%"
CDS_LIB"pure_quanta"
$SEC"1"
CDS_SEC"1";
"B"
$PN"2"22;
"A"
$PN"1"4;
%"UNIVERSAL_POWER"
"1","(150,-500)","0","logical_power","I38";
;
HDL_POWER"P12V_AUX"
CDS_LIB"logical_power";
"A"4;
%"Q_RES"
"2","(2025,-1275)","0","pure_quanta","I39";
;
PART_NUMBER"CS11002FB07"
MATERIAL"EMPTY"
PACK_TYPE"0402LF"
VALUE"100"
TOLERANCE"1%"
WATTAGE"1/16W"
LOCATION"PR4006"
CDS_LIB"pure_quanta"
$SEC"1"
CDS_SEC"1";
"A"
$PN"1"3;
"B"
$PN"2"34;
%"GND"
"1","(-1125,-2050)","0","logical_power","I4";
;
CDS_LIB"logical_power"
SIZE"1B"
HDL_POWER"GND";
"A<SIZE-1..0>\NAC"31;
%"Q_CAP"
"1","(2100,-2125)","0","pure_quanta","I42";
;
PART_NUMBER"CH4106K1B01"
ROOM"SCM_P12V_BOM2"
VOLTAGE"50V"
PACK_TYPE"C0402"
MATERIAL"X7R"
VALUE"100NF"
LOCATION"PC2235"
TOLERANCE"10%"
CDS_LIB"pure_quanta"
$SEC"1"
CDS_SEC"1";
"B"
$PN"2"20;
"A"
$PN"1"38;
%"GND"
"1","(2100,-2525)","0","logical_power","I43";
;
SIZE"1B"
CDS_LIB"logical_power"
HDL_POWER"GND";
"A<SIZE-1..0>\NAC"20;
%"Q_RES"
"1","(2700,-2300)","0","pure_quanta","I44";
;
PART_NUMBER"CS00002JB13"
MATERIAL"CHIP"
ROOM"SCM_P12V_BOM2"
VALUE"0"
TOLERANCE"5%"
WATTAGE"1/16W"
PACK_TYPE"0402LF"
$LOCATION"R4709"
CDS_LIB"pure_quanta"
CDS_LOCATION"R4709"
$SEC"1"
CDS_SEC"1";
"B"
$PN"2"55;
"A"
$PN"1"37;
%"GND"
"1","(3225,-2100)","0","logical_power","I45";
;
SIZE"1B"
CDS_LIB"logical_power"
HDL_POWER"GND";
"A<SIZE-1..0>\NAC"19;
%"Q_RES"
"1","(2475,-1750)","0","pure_quanta","I48";
;
PART_NUMBER"CS31002FB08"
ROOM"SCM_P12V_BOM2"
MATERIAL"CHIP"
WATTAGE"1/16W"
TOLERANCE"1%"
VALUE"10K"
PACK_TYPE"0402LF"
LOCATION"PR4007"
CDS_LIB"pure_quanta"
$SEC"1"
CDS_SEC"1";
"B"
$PN"2"9;
"A"
$PN"1"37;
%"VCCAUX15"
"1","(2850,-1675)","0","logical_power","I49";
;
HDL_POWER"P3V3_AUX"
CDS_LIB"logical_power";
"A"9;
%"GND"
"1","(-675,-2125)","0","logical_power","I5";
;
SIZE"1B"
CDS_LIB"logical_power"
HDL_POWER"GND";
"A<SIZE-1..0>\NAC"30;
%"Q_RES"
"2","(3025,-1775)","0","pure_quanta","I50";
;
PART_NUMBER"CS31002FB08"
ROOM"SCM_P12V_BOM2"
VALUE"10K"
TOLERANCE"1%"
MATERIAL"CHIP"
WATTAGE"1/16W"
PACK_TYPE"0402LF"
LOCATION"PR4011"
CDS_LIB"pure_quanta"
$SEC"1"
CDS_SEC"1";
"A"
$PN"1"33;
"B"
$PN"2"19;
%"Q_RES"
"2","(2625,-1275)","0","pure_quanta","I51";
;
PART_NUMBER"CS37152FB05"
VALUE"71.5K"
PACK_TYPE"0402LF"
MATERIAL"EMPTY"
TOLERANCE"1%"
LOCATION"PR4009"
CDS_LIB"pure_quanta"
WATTAGE"1/16W"
$SEC"1"
CDS_SEC"1";
"A"
$PN"1"3;
"B"
$PN"2"33;
%"Q_RES"
"2","(3025,-1350)","0","pure_quanta","I52";
;
PART_NUMBER"CS41202FB05"
WATTAGE"1/16W"
MATERIAL"CHIP"
VALUE"120K"
PACK_TYPE"0402LF"
TOLERANCE"1%"
ROOM"SCM_P12V_BOM2"
LOCATION"PR4010"
CDS_LIB"pure_quanta"
$SEC"1"
CDS_SEC"1";
"A"
$PN"1"10;
"B"
$PN"2"33;
%"Q_CAP"
"1","(3550,-1775)","0","pure_quanta","I53";
;
PART_NUMBER"CH5223M1900"
ROOM"SCM_P12V_BOM2"
VOLTAGE"16V"
VALUE"2.2UF"
TOLERANCE"20%"
MATERIAL"X7R"
PACK_TYPE"C0603"
LOCATION"PC2239"
CDS_LIB"pure_quanta"
$SEC"1"
CDS_SEC"1";
"B"
$PN"2"19;
"A"
$PN"1"54;
%"Q_RES"
"2","(3550,-1350)","0","pure_quanta","I54";
;
PART_NUMBER"CS04993F909"
PACK_TYPE"0603LF"
TOLERANCE"1%"
WATTAGE"1/10W"
MATERIAL"CHIP"
VALUE"49.9"
ROOM"SCM_P12V_BOM2"
LOCATION"PR4014"
CDS_LIB"pure_quanta"
$SEC"1"
CDS_SEC"1";
"A"
$PN"1"10;
"B"
$PN"2"54;
%"UNIVERSAL_POWER"
"1","(3550,-1050)","0","logical_power","I55";
;
HDL_POWER"P12V_AUX"
CDS_LIB"logical_power";
"A"10;
%"GND"
"1","(3900,-1200)","0","logical_power","I56";
;
SIZE"1B"
CDS_LIB"logical_power"
HDL_POWER"GND";
"A<SIZE-1..0>\NAC"18;
%"Q_CAP"
"1","(3900,-925)","2","pure_quanta","I57";
;
PART_NUMBER"CH4104K1B00"
MATERIAL"X7R"
ROOM"SCM_P12V_BOM2"
VOLTAGE"25V"
VALUE"0.1UF"
TOLERANCE"10%"
PACK_TYPE"0402"
LOCATION"PC2241"
CDS_LIB"pure_quanta"
$SEC"1"
CDS_SEC"1";
"B"
$PN"2"18;
"A"
$PN"1"3;
%"UNIVERSAL_POWER"
"1","(3900,-650)","2","logical_power","I58";
;
HDL_POWER"P12V_SCM_R"
CDS_LIB"logical_power";
"A"3;
%"GND"
"1","(-250,-2375)","0","logical_power","I6";
;
SIZE"1B"
CDS_LIB"logical_power"
HDL_POWER"GND";
"A<SIZE-1..0>\NAC"29;
%"GND"
"1","(75,750)","0","logical_power","I60";
;
CDS_LIB"logical_power"
SIZE"1B"
HDL_POWER"GND";
"A<SIZE-1..0>\NAC"17;
%"Q_RES"
"2","(75,975)","0","pure_quanta","I61";
;
PART_NUMBER"CS31502FB05"
ROOM"SCM_P12V_BOM1"
TOLERANCE"1%"
WATTAGE"1/16W"
MATERIAL"EMPTY"
VALUE"15K"
PACK_TYPE"0402LF"
LOCATION"PR4002"
CDS_LIB"pure_quanta"
$SEC"1"
CDS_SEC"1";
"A"
$PN"1"52;
"B"
$PN"2"17;
%"GND"
"1","(925,750)","0","logical_power","I62";
;
SIZE"1B"
CDS_LIB"logical_power"
HDL_POWER"GND";
"A<SIZE-1..0>\NAC"16;
%"Q_RES"
"2","(925,975)","0","pure_quanta","I63";
;
PART_NUMBER"CS31782FB04"
PACK_TYPE"0402LF"
WATTAGE"1/16W"
MATERIAL"EMPTY"
TOLERANCE"1%"
VALUE"17.8K"
ROOM"SCM_P12V_BOM1"
LOCATION"PR4004"
CDS_LIB"pure_quanta"
$SEC"1"
CDS_SEC"1";
"A"
$PN"1"51;
"B"
$PN"2"16;
%"Q_RES"
"2","(75,1250)","0","pure_quanta","I64";
;
PART_NUMBER"CS26802FB02"
MATERIAL"EMPTY"
PACK_TYPE"0402LF"
ROOM"SCM_P12V_BOM1"
VALUE"6.8K"
TOLERANCE"1%"
WATTAGE"1/16W"
LOCATION"PR4001"
CDS_LIB"pure_quanta"
$SEC"1"
CDS_SEC"1";
"A"
$PN"1"53;
"B"
$PN"2"52;
%"GND"
"1","(400,1425)","0","logical_power","I65";
;
SIZE"1B"
CDS_LIB"logical_power"
HDL_POWER"GND";
"A<SIZE-1..0>\NAC"15;
%"Q_CAP"
"1","(625,1500)","1","pure_quanta","I66";
;
PART_NUMBER"CH5104KEB02"
PACK_TYPE"C0402"
VOLTAGE"25V"
VALUE"1UF"
ROOM"SCM_P12V_BOM1"
LOCATION"PC2234"
MATERIAL"EMPTY"
TOLERANCE"10%"
CDS_LIB"pure_quanta"
$SEC"1"
CDS_SEC"1";
"B"
$PN"2"49;
"A"
$PN"1"15;
%"Q_RES"
"2","(75,1925)","0","pure_quanta","I67";
;
PART_NUMBER"CS41602FB05"
TOLERANCE"1%"
PACK_TYPE"0402LF"
ROOM"SCM_P12V_BOM1"
VALUE"160K"
WATTAGE"1/16W"
MATERIAL"EMPTY"
LOCATION"PR4000"
CDS_LIB"pure_quanta"
$SEC"1"
CDS_SEC"1";
"A"
$PN"1"5;
"B"
$PN"2"53;
%"Q_CAP"
"1","(400,1800)","0","pure_quanta","I68";
;
PART_NUMBER"CH5104KEB02"
VOLTAGE"25V"
PACK_TYPE"C0402"
VALUE"1UF"
MATERIAL"EMPTY"
ROOM"SCM_P12V_BOM1"
LOCATION"PC2233"
TOLERANCE"10%"
CDS_LIB"pure_quanta"
$SEC"1"
CDS_SEC"1";
"B"
$PN"2"15;
"A"
$PN"1"50;
%"MAX15090BEWIT"
"1","(1675,1500)","0","pure_quanta","I69";
;
PART_NUMBER"AL015080B00"
PART_TYPE"SMLF"
MATERIAL"EMPTY"
VALUE"MAX15090BEWI+T"
ROOM"SCM_P12V_BOM1"
LOCATION"PU300"
CDS_LMAN_SYM_OUTLINE"-250,550,250,-550"
CDS_LIB"pure_quanta"
PIN_NAMES_ROTATE"TRUE"
$SEC"1"
CDS_SEC"1";
"PG"
$PN"D7"47;
"FAULT# \B"
$PN"C7"46;
"GND_C2"
$PN"C2"14;
"GND_C1"
$PN"C1"14;
"GND_B2"
$PN"B2"14;
"CDLY"
$PN"A7"14;
"GATE"
$PN"A6"43;
"OUT_D6"
$PN"D6"1;
"OUT_D4"
$PN"D4"1;
"OUT_C6"
$PN"C6"1;
"OUT_C4"
$PN"C4"1;
"OUT_B6"
$PN"B6"1;
"OUT_B4"
$PN"B4"1;
"OUT_A4"
$PN"A4"1;
"ISENSE"
$PN"A1"48;
"OV"
$PN"D3"52;
"UV"
$PN"D2"53;
"REG"
$PN"D1"49;
"EN# \B"
$PN"B7"16;
"CB"
$PN"B1"51;
"IN_D5"
$PN"D5"5;
"IN_C5"
$PN"C5"5;
"IN_C3"
$PN"C3"5;
"IN_B5"
$PN"B5"5;
"IN_B3"
$PN"B3"5;
"IN_A5"
$PN"A5"5;
"IN_A3"
$PN"A3"5;
"VCC"
$PN"A2"50;
%"Q_CAP"
"1","(-250,-2150)","0","pure_quanta","I7";
;
PART_NUMBER"CH1566K1B09"
VOLTAGE"50V"
ROOM"SCM_P12V_BOM2"
VALUE"560PF"
PACK_TYPE"C0402"
MATERIAL"X7R"
LOCATION"PC2340"
TOLERANCE"10%"
CDS_LIB"pure_quanta"
$SEC"1"
CDS_SEC"1";
"B"
$PN"2"29;
"A"
$PN"1"60;
%"Q_RES"
"2","(400,2225)","0","pure_quanta","I70";
;
PART_NUMBER"CS01002FB07"
PACK_TYPE"0402LF"
WATTAGE"1/16W"
VALUE"10"
TOLERANCE"1%"
MATERIAL"EMPTY"
ROOM"SCM_P12V_BOM1"
LOCATION"PR4003"
CDS_LIB"pure_quanta"
$SEC"1"
CDS_SEC"1";
"A"
$PN"1"5;
"B"
$PN"2"50;
%"GND"
"1","(2400,750)","0","logical_power","I71";
;
CDS_LIB"logical_power"
SIZE"1B"
HDL_POWER"GND";
"A<SIZE-1..0>\NAC"14;
%"Q_RES"
"2","(2525,1125)","0","pure_quanta","I72";
;
PART_NUMBER"CS21332FB05"
ROOM"SCM_P12V_BOM1"
VALUE"1.33K"
WATTAGE"1/16W"
PACK_TYPE"0402LF"
MATERIAL"EMPTY"
TOLERANCE"1%"
LOCATION"PR4008"
CDS_LIB"pure_quanta"
$SEC"1"
CDS_SEC"1";
"A"
$PN"1"48;
"B"
$PN"2"14;
%"Q_CAP"
"1","(2475,1825)","0","pure_quanta","I73";
;
PART_NUMBER"CH31006KB18"
VOLTAGE"50V"
VALUE"0.01UF"
MATERIAL"EMPTY"
PACK_TYPE"C0402"
LOCATION"PC2236"
CDS_LIB"pure_quanta"
TOLERANCE"10%"
$SEC"1"
CDS_SEC"1";
"B"
$PN"2"43;
"A"
$PN"1"1;
%"Q_RES"
"1","(3150,1500)","0","pure_quanta","I74";
;
PART_NUMBER"CS00002JB13"
MATERIAL"EMPTY"
PACK_TYPE"0402LF"
WATTAGE"1/16W"
VALUE"0"
ROOM"SCM_P12V_BOM1"
TOLERANCE"5%"
LOCATION"PR4012"
CDS_LIB"pure_quanta"
$SEC"1"
CDS_SEC"1";
"B"
$PN"2"45;
"A"
$PN"1"47;
%"Q_CAP"
"1","(3075,1600)","1","pure_quanta","I75";
;
PART_NUMBER"CH23906KB14"
ROOM"SCM_P12V_BOM1"
PACK_TYPE"C0402"
VALUE"3900PF"
VOLTAGE"50V"
LOCATION"PC2237"
MATERIAL"EMPTY"
TOLERANCE"10%"
CDS_LIB"pure_quanta"
$SEC"1"
CDS_SEC"1";
"B"
$PN"2"13;
"A"
$PN"1"43;
%"Q_RES"
"2","(2800,1850)","0","pure_quanta","I76";
;
PART_NUMBER"CS61002FB02"
PACK_TYPE"0402LF"
WATTAGE"1/16W"
VALUE"10M"
ROOM"SCM_P12V_BOM1"
TOLERANCE"1%"
MATERIAL"EMPTY"
LOCATION"PR4526"
CDS_LIB"pure_quanta"
$SEC"1"
CDS_SEC"1";
"A"
$PN"1"1;
"B"
$PN"2"43;
%"Q_RES"
"1","(3225,1400)","0","pure_quanta","I77";
;
PART_NUMBER"CS00002JB13"
MATERIAL"EMPTY"
ROOM"SCM_P12V_BOM1"
VALUE"0"
TOLERANCE"5%"
PACK_TYPE"0402LF"
WATTAGE"1/16W"
$LOCATION"R4708"
CDS_LIB"pure_quanta"
CDS_LOCATION"R4708"
$SEC"1"
CDS_SEC"1";
"B"
$PN"2"35;
"A"
$PN"1"46;
%"GND"
"1","(3275,1550)","0","logical_power","I78";
;
CDS_LIB"logical_power"
SIZE"1B"
HDL_POWER"GND";
"A<SIZE-1..0>\NAC"13;
%"Q_RES"
"2","(3500,1750)","0","pure_quanta","I79";
;
PART_NUMBER"CS41002FB09"
ROOM"SCM_P12V_BOM1"
WATTAGE"1/16W"
MATERIAL"EMPTY"
PACK_TYPE"0402LF"
VALUE"100K"
TOLERANCE"1%"
LOCATION"R4013"
CDS_LIB"pure_quanta"
$SEC"1"
CDS_SEC"1";
"A"
$PN"1"2;
"B"
$PN"2"35;
%"Q_CAP"
"1","(-1125,-1750)","0","pure_quanta","I8";
;
PART_NUMBER"CH4223K1B00"
ROOM"SCM_P12V_BOM2"
MATERIAL"X7R"
PACK_TYPE"0402"
VALUE"0.22UF"
VOLTAGE"16V"
LOCATION"PC2229"
TOLERANCE"10%"
CDS_LIB"pure_quanta"
$SEC"1"
CDS_SEC"1";
"B"
$PN"2"31;
"A"
$PN"1"40;
%"VCCAUX15"
"1","(3700,2100)","0","logical_power","I80";
;
HDL_POWER"P3V3_AUX"
CDS_LIB"logical_power";
"A"2;
%"Q_RES"
"2","(3925,1750)","0","pure_quanta","I81";
;
PART_NUMBER"CS41002FB09"
PACK_TYPE"0402LF"
MATERIAL"EMPTY"
WATTAGE"1/16W"
VALUE"100K"
ROOM"SCM_P12V_BOM1"
TOLERANCE"1%"
LOCATION"R4015"
CDS_LIB"pure_quanta"
$SEC"1"
CDS_SEC"1";
"A"
$PN"1"2;
"B"
$PN"2"45;
%"SCHOTTKY_AC"
"1","(2900,2450)","1","pure_quanta","I82";
;
PART_NUMBER"BC000340Z30"
VALUE"B340A-13-F"
MATERIAL"IC"
LOCATION"PD116"
CDS_LIB"pure_quanta"
CDS_LMAN_SYM_OUTLINE"-75,50,75,-50"
NEEDS_NO_SIZE"TRUE"
PART_TYPE"SMLF"
$SEC"1"
CDS_SEC"1";
"C"
$PN"C"1;
"A"
$PN"A"12;
%"Q_CAP"
"1","(3375,2425)","0","pure_quanta","I83";
;
PART_NUMBER"CH4104K1B00"
PACK_TYPE"0402"
VALUE"0.1UF"
VOLTAGE"25V"
MATERIAL"X7R"
LOCATION"PC2238"
CDS_LIB"pure_quanta"
TOLERANCE"10%"
$SEC"1"
CDS_SEC"1";
"B"
$PN"2"12;
"A"
$PN"1"1;
%"Q_CAP"
"1","(3800,2425)","0","pure_quanta","I84";
;
PART_NUMBER"CH6103KEA03"
MATERIAL"X6S"
VALUE"10UF"
VOLTAGE"16V"
PACK_TYPE"C0805"
LOCATION"PC2240"
CDS_LIB"pure_quanta"
TOLERANCE"10%"
$SEC"1"
CDS_SEC"1";
"B"
$PN"2"12;
"A"
$PN"1"1;
%"GND"
"1","(4200,2125)","0","logical_power","I87";
;
SIZE"1B"
CDS_LIB"logical_power"
HDL_POWER"GND";
"A<SIZE-1..0>\NAC"12;
%"Q_CAP"
"1","(4200,2425)","0","pure_quanta","I88";
;
PART_NUMBER"CH6223MEA03"
VOLTAGE"16V"
VALUE"22UF"
MATERIAL"X6S"
PACK_TYPE"C0805"
LOCATION"PC2242"
CDS_LIB"pure_quanta"
TOLERANCE"20%"
$SEC"1"
CDS_SEC"1";
"B"
$PN"2"12;
"A"
$PN"1"1;
%"UNIVERSAL_POWER"
"1","(4200,2725)","2","logical_power","I89";
;
HDL_POWER"P12V_SCM_R"
CDS_LIB"logical_power";
"A"1;
%"MOSFET_NCH_GDS_ESD_PROTECTED"
"1","(-1375,-225)","0","pure_quanta","I9";
;
PART_NUMBER"BAM70020002"
VALUE"2N7002K"
PART_TYPE"SMLF"
MATERIAL"IC"
$LOCATION"Q39"
NEEDS_NO_SIZE"TRUE"
CDS_LIB"pure_quanta"
CDS_LMAN_SYM_OUTLINE"-125,150,125,-150"
CDS_LOCATION"Q39"
$SEC"1"
CDS_SEC"1";
"S"
$PN"S"28;
"G"
$PN"G"61;
"D"
$PN"D"44;
%"RS31312R"
"1","(1025,-1375)","0","pure_quanta","I90";
;
PART_NUMBER"AL031312000"
VALUE"RS31312R"
MATERIAL"IC"
ROOM"SCM_P12V_BOM2"
LOCATION"PU299"
PART_TYPE"SMLF"
CDS_LIB"pure_quanta"
NEEDS_NO_SIZE"TRUE"
CDS_LMAN_SYM_OUTLINE"-250,525,250,-525"
$SEC"1"
CDS_SEC"1";
"GND"
$PN"7"21;
"SS"
$PN"6"42;
"ISET"
$PN"5"41;
"TIMER"
$PN"4"40;
"ENTM"
$PN"3"27;
"LOADEN"
$PN"2"27;
"EN"
$PN"1"39;
"VIN_26"
$PN"26"4;
"VIN_25"
$PN"25"4;
"VIN_24"
$PN"24"4;
"VIN_23"
$PN"23"4;
"IMON"
$PN"8"38;
"FLTB"
$PN"9"37;
"PG"
$PN"10"36;
"OV"
$PN"11"33;
"VOUT_13"
$PN"13"3;
"AVIN"
$PN"12"34;
"VOUT_14"
$PN"14"3;
"VOUT_15"
$PN"15"3;
"VOUT_16"
$PN"16"3;
"VOUT_17"
$PN"17"3;
"VOUT_18"
$PN"18"3;
"VOUT_19"
$PN"19"3;
"VIN_21_22"
$PN"21_22"4;
"VOUT_20"
$PN"20"3;
%"Q_RES"
"1","(2425,-900)","0","pure_quanta","I91";
;
PART_NUMBER"CS00002JB13"
VALUE"0"
ROOM"SCM_P12V_BOM2"
MATERIAL"CHIP"
PACK_TYPE"0402LF"
$LOCATION"R4770"
CDS_LIB"pure_quanta"
TOLERANCE"5%"
WATTAGE"1/16W"
CDS_LOCATION"R4770"
$SEC"1"
CDS_SEC"1";
"B"
$PN"2"32;
"A"
$PN"1"36;
%"Q_RES"
"2","(2275,-650)","0","pure_quanta","I92";
;
PART_NUMBER"CS31002FB08"
PACK_TYPE"0402LF"
MATERIAL"CHIP"
ROOM"SCM_P12V_BOM2"
WATTAGE"1/16W"
TOLERANCE"1%"
VALUE"10K"
LOCATION"R3836"
CDS_LIB"pure_quanta"
$SEC"1"
CDS_SEC"1";
"A"
$PN"1"11;
"B"
$PN"2"36;
%"VCCAUX15"
"1","(2275,-450)","0","logical_power","I93";
;
HDL_POWER"P3V3_AUX"
CDS_LIB"logical_power";
"A"11;
END.
